(kicad_pcb
	(version 20260206)
	(generator "pcbnew")
	(generator_version "10.0")
	(general
		(thickness 1.6)
		(legacy_teardrops no)
	)
	(paper "A4")
	(title_block
		(title "panther-plus-userver — 13130-1b_20150205.brd")
		(comment 1 "Honey Badger (Wiwynn) / footprints 105-112 of 1509")
	)
	(layers
		(0 "F.Cu" signal "TOP")
		(4 "In1.Cu" signal "L2")
		(6 "In2.Cu" signal "L3")
		(8 "In3.Cu" signal "L4")
		(10 "In4.Cu" signal "L5")
		(12 "In5.Cu" signal "L6")
		(14 "In6.Cu" signal "L7")
		(16 "In7.Cu" signal "L8")
		(18 "In8.Cu" signal "L9")
		(20 "In9.Cu" signal "L10")
		(22 "In10.Cu" signal "L11")
		(2 "B.Cu" signal "BOTTOM")
		(9 "F.Adhes" user "F.Adhesive")
		(11 "B.Adhes" user "B.Adhesive")
		(13 "F.Paste" user "Package Geometry/Pastemask Top")
		(15 "B.Paste" user "Package Geometry/Pastemask Bottom")
		(5 "F.SilkS" user "Ref Des/Silkscreen Top")
		(7 "B.SilkS" user "Ref Des/Silkscreen Bottom")
		(1 "F.Mask" user "Board Geometry/Soldermask Top")
		(3 "B.Mask" user "Board Geometry/Soldermask Bottom")
		(17 "Dwgs.User" user "User.Drawings")
		(19 "Cmts.User" user "User.Comments")
		(21 "Eco1.User" user "User.Eco1")
		(23 "Eco2.User" user "User.Eco2")
		(25 "Edge.Cuts" user "Board Geometry/Outline")
		(27 "Margin" user)
		(31 "F.CrtYd" user "Package Geometry/Place Bound Top")
		(29 "B.CrtYd" user "Package Geometry/Place Bound Bottom")
		(35 "F.Fab" user "Ref Des/Assembly Top")
		(33 "B.Fab" user "Ref Des/Assembly Bottom")
	)
	(footprint ""
		(layer "F.Cu")
		(at 11.176 -59.436 180)
		(property "Reference" "TP5"
			(at 0 0 180)
			(layer "F.SilkS")
			(hide yes)
			(effects
				(font
					(size 1.27 1.27)
				)
			)
		)
		(property "Value" "TPAD28-1-GP-U"
			(at 0.0508 -1.9304 180)
			(unlocked yes)
			(layer "F.Fab")
			(hide yes)
			(effects
				(font
					(size 1.016 1.016)
					(thickness 0.1524)
				)
			)
		)
		(property "Device Type" "TPAD28-1-U"
			(at 0.0508 -3.4544 180)
			(unlocked yes)
			(layer "F.Fab")
			(hide yes)
			(effects
				(font
					(size 1.016 1.016)
					(thickness 0.1524)
				)
			)
		)
		(duplicate_pad_numbers_are_jumpers no)
		(fp_poly
			(pts
				(arc
					(start -0.3556 0)
					(mid 0.3556 0)
					(end -0.3556 0)
				)
			)
			(stroke
				(width 0)
				(type default)
			)
			(fill no)
			(layer "F.CrtYd")
		)
		(fp_poly
			(pts
				(arc
					(start -0.9525 0)
					(mid 0.9525 0)
					(end -0.9525 0)
				)
			)
			(stroke
				(width 0)
				(type default)
			)
			(fill no)
			(layer "F.Fab")
		)
		(pad "1" smd circle
			(at 0 0 180)
			(size 0.7112 0.7112)
			(layers "F.Cu" "F.Mask" "F.Paste")
			(net "TP_PVCCP_ALERT")
		)
	)
	(footprint ""
		(layer "F.Cu")
		(at 38.1508 -54.483)
		(property "Reference" "PC33"
			(at 0 0 0)
			(layer "F.SilkS")
			(hide yes)
			(effects
				(font
					(size 1.27 1.27)
				)
			)
		)
		(property "Value" "SCD1U25V2KX-2-GP"
			(at 1.8923 -1.2065 0)
			(unlocked yes)
			(layer "F.Fab")
			(hide yes)
			(effects
				(font
					(size 1.016 1.016)
					(thickness 0.1524)
				)
			)
		)
		(property "Device Type" "C402H22"
			(at 1.8923 -2.7305 0)
			(unlocked yes)
			(layer "F.Fab")
			(hide yes)
			(effects
				(font
					(size 1.016 1.016)
					(thickness 0.1524)
				)
			)
		)
		(duplicate_pad_numbers_are_jumpers no)
		(fp_rect
			(start -0.381 0.7366)
			(end 0.381 -0.7366)
			(stroke
				(width 0)
				(type default)
			)
			(fill no)
			(layer "F.CrtYd")
		)
		(fp_rect
			(start -0.381 0.7366)
			(end 0.381 -0.7366)
			(stroke
				(width 0)
				(type default)
			)
			(fill no)
			(layer "F.Fab")
		)
		(pad "1" smd custom
			(at 0 -0.4572)
			(size 0.1143 0.1143)
			(layers "F.Cu" "F.Mask" "F.Paste")
			(net "VR_FET_SW_P12V_PVCCP_PVNN")
			(options
				(clearance outline)
				(anchor circle)
			)
			(primitives
				(gr_poly
					(pts
						(arc
							(start -0.254 -0.1778)
							(mid -0.239121 -0.213721)
							(end -0.2032 -0.2286)
						)
						(arc
							(start 0.2032 -0.2286)
							(mid 0.239121 -0.213721)
							(end 0.254 -0.1778)
						)
						(arc
							(start 0.254 0.1778)
							(mid 0.239121 0.213721)
							(end 0.2032 0.2286)
						)
						(arc
							(start -0.2032 0.2286)
							(mid -0.239121 0.213721)
							(end -0.254 0.1778)
						)
					)
					(width 0)
					(fill yes)
				)
			)
		)
		(pad "2" smd custom
			(at 0 0.4572)
			(size 0.1143 0.1143)
			(layers "F.Cu" "F.Mask" "F.Paste")
			(net "GND")
			(options
				(clearance outline)
				(anchor circle)
			)
			(primitives
				(gr_poly
					(pts
						(arc
							(start -0.254 -0.1778)
							(mid -0.239121 -0.213721)
							(end -0.2032 -0.2286)
						)
						(arc
							(start 0.2032 -0.2286)
							(mid 0.239121 -0.213721)
							(end 0.254 -0.1778)
						)
						(arc
							(start 0.254 0.1778)
							(mid 0.239121 0.213721)
							(end 0.2032 0.2286)
						)
						(arc
							(start -0.2032 0.2286)
							(mid -0.239121 0.213721)
							(end -0.254 0.1778)
						)
					)
					(width 0)
					(fill yes)
				)
			)
		)
	)
	(footprint ""
		(layer "F.Cu")
		(at 53.467 -54.864 90)
		(property "Reference" "PRT1"
			(at 0 0 90)
			(layer "F.SilkS")
			(hide yes)
			(effects
				(font
					(size 1.27 1.27)
				)
			)
		)
		(property "Value" "NTC-10K-19-GP-U"
			(at 1.7907 -1.1176 90)
			(unlocked yes)
			(layer "F.Fab")
			(hide yes)
			(effects
				(font
					(size 1.016 1.016)
					(thickness 0.1524)
				)
			)
		)
		(property "Device Type" "NTC-402H22-U"
			(at 1.7907 -2.6416 90)
			(unlocked yes)
			(layer "F.Fab")
			(hide yes)
			(effects
				(font
					(size 1.016 1.016)
					(thickness 0.1524)
				)
			)
		)
		(duplicate_pad_numbers_are_jumpers no)
		(fp_rect
			(start -0.381 0.8382)
			(end 0.381 -0.8382)
			(stroke
				(width 0)
				(type default)
			)
			(fill no)
			(layer "F.CrtYd")
		)
		(fp_rect
			(start -0.381 0.8382)
			(end 0.381 -0.8382)
			(stroke
				(width 0)
				(type default)
			)
			(fill no)
			(layer "F.Fab")
		)
		(pad "1" smd custom
			(at 0 -0.4318 90)
			(size 0.127 0.127)
			(layers "F.Cu" "F.Mask" "F.Paste")
			(net "VR_PVCCP_ISUMN")
			(options
				(clearance outline)
				(anchor circle)
			)
			(primitives
				(gr_poly
					(pts
						(arc
							(start -0.2032 -0.2794)
							(mid -0.239121 -0.264521)
							(end -0.254 -0.2286)
						)
						(arc
							(start -0.254 0.2286)
							(mid -0.239121 0.264521)
							(end -0.2032 0.2794)
						)
						(arc
							(start 0.2032 0.2794)
							(mid 0.239121 0.264521)
							(end 0.254 0.2286)
						)
						(arc
							(start 0.254 -0.2286)
							(mid 0.239121 -0.264521)
							(end 0.2032 -0.2794)
						)
					)
					(width 0)
					(fill yes)
				)
			)
		)
		(pad "2" smd custom
			(at 0 0.4318 90)
			(size 0.127 0.127)
			(layers "F.Cu" "F.Mask" "F.Paste")
			(net "VR_PVCCP_NTC")
			(options
				(clearance outline)
				(anchor circle)
			)
			(primitives
				(gr_poly
					(pts
						(arc
							(start -0.2032 -0.2794)
							(mid -0.239121 -0.264521)
							(end -0.254 -0.2286)
						)
						(arc
							(start -0.254 0.2286)
							(mid -0.239121 0.264521)
							(end -0.2032 0.2794)
						)
						(arc
							(start 0.2032 0.2794)
							(mid 0.239121 0.264521)
							(end 0.254 0.2286)
						)
						(arc
							(start 0.254 -0.2286)
							(mid 0.239121 -0.264521)
							(end 0.2032 -0.2794)
						)
					)
					(width 0)
					(fill yes)
				)
			)
		)
	)
	(footprint ""
		(layer "F.Cu")
		(at 187.198 -48.26 90)
		(property "Reference" "U27"
			(at 0 0 90)
			(layer "F.SilkS")
			(hide yes)
			(effects
				(font
					(size 1.27 1.27)
				)
			)
		)
		(property "Value" "LMV321IDCKR-1-GP"
			(at -2.3368 -8.6868 90)
			(unlocked yes)
			(layer "F.Fab")
			(hide yes)
			(effects
				(font
					(size 1.016 1.016)
					(thickness 0.1524)
				)
			)
		)
		(property "Device Type" "SC70-5H44"
			(at -2.3114 -10.414 90)
			(unlocked yes)
			(layer "F.Fab")
			(hide yes)
			(effects
				(font
					(size 1.016 1.016)
					(thickness 0.1524)
				)
			)
		)
		(duplicate_pad_numbers_are_jumpers no)
		(fp_line
			(start 1.0033 -0.3302)
			(end 1.0033 0.3302)
			(stroke
				(width 0.1524)
				(type default)
			)
			(layer "F.SilkS")
		)
		(fp_line
			(start -1.0033 -0.3302)
			(end 1.0033 -0.3302)
			(stroke
				(width 0.1524)
				(type default)
			)
			(layer "F.SilkS")
		)
		(fp_line
			(start 1.0033 0.3302)
			(end -1.0033 0.3302)
			(stroke
				(width 0.1524)
				(type default)
			)
			(layer "F.SilkS")
		)
		(fp_line
			(start -1.0033 0.3302)
			(end -1.0033 -0.3302)
			(stroke
				(width 0.1524)
				(type default)
			)
			(layer "F.SilkS")
		)
		(fp_poly
			(pts
				(xy -1.0033 1.4859) (xy -1.0033 0.8001) (xy -1.1811 0.8001) (xy -1.1811 -0.8001) (xy -1.0033 -0.8001)
				(xy -1.0033 -1.4859) (xy 1.0033 -1.4859) (xy 1.0033 -0.8001) (xy 1.1811 -0.8001) (xy 1.1811 0.8001)
				(xy 1.0033 0.8001) (xy 1.0033 1.4859) (xy 0.2921 1.4859) (xy 0.2921 0.8001) (xy -0.2921 0.8001)
				(xy -0.2921 1.4859)
			)
			(stroke
				(width 0)
				(type default)
			)
			(fill no)
			(layer "F.CrtYd")
		)
		(fp_poly
			(pts
				(xy -1.0033 1.4859) (xy -1.0033 0.8001) (xy -1.1811 0.8001) (xy -1.1811 -0.8001) (xy -1.0033 -0.8001)
				(xy -1.0033 -1.4859) (xy 1.0033 -1.4859) (xy 1.0033 -0.8001) (xy 1.1811 -0.8001) (xy 1.1811 0.8001)
				(xy 1.0033 0.8001) (xy 1.0033 1.4859) (xy 0.2921 1.4859) (xy 0.2921 0.8001) (xy -0.2921 0.8001)
				(xy -0.2921 1.4859)
			)
			(stroke
				(width 0)
				(type default)
			)
			(fill no)
			(layer "F.Fab")
		)
		(pad "1" smd rect
			(at 0.65024 -0.93472 90)
			(size 0.3556 0.762)
			(layers "F.Cu" "F.Mask" "F.Paste")
			(net "PV_VDDR_VREF_RW")
		)
		(pad "2" smd rect
			(at 0 -0.93472 90)
			(size 0.3556 0.762)
			(layers "F.Cu" "F.Mask" "F.Paste")
			(net "GND")
		)
		(pad "3" smd rect
			(at -0.65024 -0.93472 90)
			(size 0.3556 0.762)
			(layers "F.Cu" "F.Mask" "F.Paste")
			(net "PV_VDDR_VREF_B_FB")
		)
		(pad "4" smd rect
			(at -0.65024 0.93472 90)
			(size 0.3556 0.762)
			(layers "F.Cu" "F.Mask" "F.Paste")
			(net "PV_VDDR_VREF_B_FB")
		)
		(pad "5" smd rect
			(at 0.65024 0.93472 90)
			(size 0.3556 0.762)
			(layers "F.Cu" "F.Mask" "F.Paste")
			(net "P3V3_STBY")
		)
	)
	(footprint ""
		(layer "F.Cu")
		(at 128.143 -37.592 -90)
		(property "Reference" "R31"
			(at 0 0 270)
			(layer "F.SilkS")
			(hide yes)
			(effects
				(font
					(size 1.27 1.27)
				)
			)
		)
		(property "Value" "33R2F-3-GP"
			(at 0.064008 -3.993896 270)
			(unlocked yes)
			(layer "F.Fab")
			(hide yes)
			(effects
				(font
					(size 1.016 1.016)
					(thickness 0.1524)
				)
			)
		)
		(property "Device Type" "R402H16"
			(at 0.064008 -5.517896 270)
			(unlocked yes)
			(layer "F.Fab")
			(hide yes)
			(effects
				(font
					(size 1.016 1.016)
					(thickness 0.1524)
				)
			)
		)
		(duplicate_pad_numbers_are_jumpers no)
		(fp_rect
			(start -0.381 0.8382)
			(end 0.381 -0.8382)
			(stroke
				(width 0)
				(type default)
			)
			(fill no)
			(layer "F.CrtYd")
		)
		(fp_rect
			(start -0.381 0.8382)
			(end 0.381 -0.8382)
			(stroke
				(width 0)
				(type default)
			)
			(fill no)
			(layer "F.Fab")
		)
		(pad "1" smd custom
			(at 0 -0.4318 270)
			(size 0.127 0.127)
			(layers "F.Cu" "F.Mask" "F.Paste")
			(net "LPC_AD_3")
			(options
				(clearance outline)
				(anchor circle)
			)
			(primitives
				(gr_poly
					(pts
						(arc
							(start -0.2032 -0.2794)
							(mid -0.239121 -0.264521)
							(end -0.254 -0.2286)
						)
						(arc
							(start -0.254 0.2286)
							(mid -0.239121 0.264521)
							(end -0.2032 0.2794)
						)
						(arc
							(start 0.2032 0.2794)
							(mid 0.239121 0.264521)
							(end 0.254 0.2286)
						)
						(arc
							(start 0.254 -0.2286)
							(mid 0.239121 -0.264521)
							(end 0.2032 -0.2794)
						)
					)
					(width 0)
					(fill yes)
				)
			)
		)
		(pad "2" smd custom
			(at 0 0.4318 270)
			(size 0.127 0.127)
			(layers "F.Cu" "F.Mask" "F.Paste")
			(net "LPC_CPU_LAD3")
			(options
				(clearance outline)
				(anchor circle)
			)
			(primitives
				(gr_poly
					(pts
						(arc
							(start -0.2032 -0.2794)
							(mid -0.239121 -0.264521)
							(end -0.254 -0.2286)
						)
						(arc
							(start -0.254 0.2286)
							(mid -0.239121 0.264521)
							(end -0.2032 0.2794)
						)
						(arc
							(start 0.2032 0.2794)
							(mid 0.239121 0.264521)
							(end 0.254 0.2286)
						)
						(arc
							(start 0.254 -0.2286)
							(mid 0.239121 -0.264521)
							(end 0.2032 -0.2794)
						)
					)
					(width 0)
					(fill yes)
				)
			)
		)
	)
	(footprint ""
		(layer "F.Cu")
		(at 141.2748 -57.5818 -90)
		(property "Reference" "PR65"
			(at 0 0 270)
			(layer "F.SilkS")
			(hide yes)
			(effects
				(font
					(size 1.27 1.27)
				)
			)
		)
		(property "Value" "10KR2F-2-GP"
			(at 0.064008 -3.993896 270)
			(unlocked yes)
			(layer "F.Fab")
			(hide yes)
			(effects
				(font
					(size 1.016 1.016)
					(thickness 0.1524)
				)
			)
		)
		(property "Device Type" "R402H16"
			(at 0.064008 -5.517896 270)
			(unlocked yes)
			(layer "F.Fab")
			(hide yes)
			(effects
				(font
					(size 1.016 1.016)
					(thickness 0.1524)
				)
			)
		)
		(duplicate_pad_numbers_are_jumpers no)
		(fp_rect
			(start -0.381 0.8382)
			(end 0.381 -0.8382)
			(stroke
				(width 0)
				(type default)
			)
			(fill no)
			(layer "F.CrtYd")
		)
		(fp_rect
			(start -0.381 0.8382)
			(end 0.381 -0.8382)
			(stroke
				(width 0)
				(type default)
			)
			(fill no)
			(layer "F.Fab")
		)
		(pad "1" smd custom
			(at 0 -0.4318 270)
			(size 0.127 0.127)
			(layers "F.Cu" "F.Mask" "F.Paste")
			(net "P3V3_STBY")
			(options
				(clearance outline)
				(anchor circle)
			)
			(primitives
				(gr_poly
					(pts
						(arc
							(start -0.2032 -0.2794)
							(mid -0.239121 -0.264521)
							(end -0.254 -0.2286)
						)
						(arc
							(start -0.254 0.2286)
							(mid -0.239121 0.264521)
							(end -0.2032 0.2794)
						)
						(arc
							(start 0.2032 0.2794)
							(mid 0.239121 0.264521)
							(end 0.254 0.2286)
						)
						(arc
							(start 0.254 -0.2286)
							(mid 0.239121 -0.264521)
							(end 0.2032 -0.2794)
						)
					)
					(width 0)
					(fill yes)
				)
			)
		)
		(pad "2" smd custom
			(at 0 0.4318 270)
			(size 0.127 0.127)
			(layers "F.Cu" "F.Mask" "F.Paste")
			(net "PV_VTT_DDR_R_PG")
			(options
				(clearance outline)
				(anchor circle)
			)
			(primitives
				(gr_poly
					(pts
						(arc
							(start -0.2032 -0.2794)
							(mid -0.239121 -0.264521)
							(end -0.254 -0.2286)
						)
						(arc
							(start -0.254 0.2286)
							(mid -0.239121 0.264521)
							(end -0.2032 0.2794)
						)
						(arc
							(start 0.2032 0.2794)
							(mid 0.239121 0.264521)
							(end 0.254 0.2286)
						)
						(arc
							(start 0.254 -0.2286)
							(mid 0.239121 -0.264521)
							(end 0.2032 -0.2794)
						)
					)
					(width 0)
					(fill yes)
				)
			)
		)
	)
	(footprint ""
		(layer "F.Cu")
		(at 5.08 -28.829)
		(property "Reference" "PL8"
			(at 0 0 0)
			(layer "F.SilkS")
			(hide yes)
			(effects
				(font
					(size 1.27 1.27)
				)
			)
		)
		(property "Value" "BLM18PG330SN1D-GP"
			(at -0.0254 -2.0193 0)
			(unlocked yes)
			(layer "F.Fab")
			(hide yes)
			(effects
				(font
					(size 1.016 1.016)
					(thickness 0.1524)
				)
			)
		)
		(property "Device Type" "L1608-UH38"
			(at -0.0254 -3.5433 0)
			(unlocked yes)
			(layer "F.Fab")
			(hide yes)
			(effects
				(font
					(size 1.016 1.016)
					(thickness 0.1524)
				)
			)
		)
		(duplicate_pad_numbers_are_jumpers no)
		(fp_line
			(start -0.4064 0)
			(end 0.4064 0)
			(stroke
				(width 0.2032)
				(type default)
			)
			(layer "F.SilkS")
		)
		(fp_rect
			(start -0.635 1.1811)
			(end 0.635 -1.1811)
			(stroke
				(width 0)
				(type default)
			)
			(fill no)
			(layer "F.CrtYd")
		)
		(fp_rect
			(start -0.635 1.1811)
			(end 0.635 -1.1811)
			(stroke
				(width 0)
				(type default)
			)
			(fill no)
			(layer "F.Fab")
		)
		(pad "1" smd custom
			(at 0 -0.6604)
			(size 0.19685 0.19685)
			(layers "F.Cu" "F.Mask" "F.Paste")
			(net "P12V")
			(options
				(clearance outline)
				(anchor circle)
			)
			(primitives
				(gr_poly
					(pts
						(arc
							(start 0.508 -0.2921)
							(mid 0.478242 -0.363942)
							(end 0.4064 -0.3937)
						)
						(arc
							(start -0.4064 -0.3937)
							(mid -0.478242 -0.363942)
							(end -0.508 -0.2921)
						)
						(arc
							(start -0.508 0.2921)
							(mid -0.478242 0.363942)
							(end -0.4064 0.3937)
						)
						(arc
							(start 0.4064 0.3937)
							(mid 0.478242 0.363942)
							(end 0.508 0.2921)
						)
					)
					(width 0)
					(fill yes)
				)
			)
		)
		(pad "2" smd custom
			(at 0 0.6604)
			(size 0.19685 0.19685)
			(layers "F.Cu" "F.Mask" "F.Paste")
			(net "P1V0_VIN")
			(options
				(clearance outline)
				(anchor circle)
			)
			(primitives
				(gr_poly
					(pts
						(arc
							(start 0.508 -0.2921)
							(mid 0.478242 -0.363942)
							(end 0.4064 -0.3937)
						)
						(arc
							(start -0.4064 -0.3937)
							(mid -0.478242 -0.363942)
							(end -0.508 -0.2921)
						)
						(arc
							(start -0.508 0.2921)
							(mid -0.478242 0.363942)
							(end -0.4064 0.3937)
						)
						(arc
							(start 0.4064 0.3937)
							(mid 0.478242 0.363942)
							(end 0.508 0.2921)
						)
					)
					(width 0)
					(fill yes)
				)
			)
		)
	)
	(footprint ""
		(layer "F.Cu")
		(at 184.912 -26.924 180)
		(property "Reference" "PR158"
			(at 0 0 180)
			(layer "F.SilkS")
			(hide yes)
			(effects
				(font
					(size 1.27 1.27)
				)
			)
		)
		(property "Value" "0R2J-2-GP"
			(at 1.7907 -1.1176 180)
			(unlocked yes)
			(layer "F.Fab")
			(hide yes)
			(effects
				(font
					(size 1.016 1.016)
					(thickness 0.1524)
				)
			)
		)
		(property "Device Type" "R402H16"
			(at 1.7907 -2.6416 180)
			(unlocked yes)
			(layer "F.Fab")
			(hide yes)
			(effects
				(font
					(size 1.016 1.016)
					(thickness 0.1524)
				)
			)
		)
		(duplicate_pad_numbers_are_jumpers no)
		(fp_rect
			(start -0.381 0.8382)
			(end 0.381 -0.8382)
			(stroke
				(width 0)
				(type default)
			)
			(fill no)
			(layer "F.CrtYd")
		)
		(fp_rect
			(start -0.381 0.8382)
			(end 0.381 -0.8382)
			(stroke
				(width 0)
				(type default)
			)
			(fill no)
			(layer "F.Fab")
		)
		(pad "1" smd custom
			(at 0 -0.4318 180)
			(size 0.127 0.127)
			(layers "F.Cu" "F.Mask" "F.Paste")
			(net "VR_PVDDR_A_VDD")
			(options
				(clearance outline)
				(anchor circle)
			)
			(primitives
				(gr_poly
					(pts
						(arc
							(start -0.2032 -0.2794)
							(mid -0.239121 -0.264521)
							(end -0.254 -0.2286)
						)
						(arc
							(start -0.254 0.2286)
							(mid -0.239121 0.264521)
							(end -0.2032 0.2794)
						)
						(arc
							(start 0.2032 0.2794)
							(mid 0.239121 0.264521)
							(end 0.254 0.2286)
						)
						(arc
							(start 0.254 -0.2286)
							(mid 0.239121 -0.264521)
							(end 0.2032 -0.2794)
						)
					)
					(width 0)
					(fill yes)
				)
			)
		)
		(pad "2" smd custom
			(at 0 0.4318 180)
			(size 0.127 0.127)
			(layers "F.Cu" "F.Mask" "F.Paste")
			(net "VR_PVDDR_A_ISEN2")
			(options
				(clearance outline)
				(anchor circle)
			)
			(primitives
				(gr_poly
					(pts
						(arc
							(start -0.2032 -0.2794)
							(mid -0.239121 -0.264521)
							(end -0.254 -0.2286)
						)
						(arc
							(start -0.254 0.2286)
							(mid -0.239121 0.264521)
							(end -0.2032 0.2794)
						)
						(arc
							(start 0.2032 0.2794)
							(mid 0.239121 0.264521)
							(end 0.254 0.2286)
						)
						(arc
							(start 0.254 -0.2286)
							(mid 0.239121 -0.264521)
							(end 0.2032 -0.2794)
						)
					)
					(width 0)
					(fill yes)
				)
			)
		)
	)
)
